# TIMECARD (Time Appliance Project (Time Card)) — schematic netlist excerpt (pin names and nets, part order shuffled) for the footprints in the layout excerpt that follows; sources: Cadence DE-HDL packaged netlist, KiCad conversion of R4006-B0001-02_R01.brd

C220  CAPACITOR  0.1UF 10V 10%  pkg SMC_0402R_H022  page 14 : \1\ = XP2R5V_FPGA ; \2\ = SG
R200  RESISTOR  4.7KOHM 1%  pkg SMC_0402R_H016  page 10 : \1\ = UNNAMED_127_MT25QL128ABA1ESES_1 ; \2\ = XP3R3V_FPGA

(kicad_pcb
	(version 20260206)
	(generator "pcbnew")
	(generator_version "10.0")
	(general
		(thickness 1.6)
		(legacy_teardrops no)
	)
	(paper "A4")
	(title_block
		(title "timecard-production-celestica-r4006 — R4006-B0001-02_R01.brd")
		(comment 1 "Time Appliance Project (Time Card) / footprints 1045-1046 of 1113")
	)
	(layers
		(0 "F.Cu" signal "TOP")
		(4 "In1.Cu" signal "L02_GND1")
		(6 "In2.Cu" signal "L03_SIG1")
		(8 "In3.Cu" signal "L04_GND2")
		(10 "In4.Cu" signal "L05_VCC1")
		(12 "In5.Cu" signal "L06_VCC2")
		(14 "In6.Cu" signal "L07_GND3")
		(16 "In7.Cu" signal "L08_SIG2")
		(18 "In8.Cu" signal "L09_GND4")
		(2 "B.Cu" signal "BOTTOM")
		(9 "F.Adhes" user "F.Adhesive")
		(11 "B.Adhes" user "B.Adhesive")
		(13 "F.Paste" user "Package Geometry/Pastemask Top")
		(15 "B.Paste" user "Package Geometry/Pastemask Bottom")
		(5 "F.SilkS" user "Ref Des/Silkscreen Top")
		(7 "B.SilkS" user "Ref Des/Silkscreen Bottom")
		(1 "F.Mask" user "Board Geometry/Soldermask Top")
		(3 "B.Mask" user "Board Geometry/Soldermask Bottom")
		(17 "Dwgs.User" user "User.Drawings")
		(19 "Cmts.User" user "User.Comments")
		(21 "Eco1.User" user "User.Eco1")
		(23 "Eco2.User" user "User.Eco2")
		(25 "Edge.Cuts" user "Board Geometry/Outline")
		(27 "Margin" user)
		(31 "F.CrtYd" user "Package Geometry/Place Bound Top")
		(29 "B.CrtYd" user "Package Geometry/Place Bound Bottom")
		(35 "F.Fab" user "Ref Des/Assembly Top")
		(33 "B.Fab" user "Ref Des/Assembly Bottom")
	)
	(footprint ""
		(layer "B.Cu")
		(at 110.847124 -37.323268 -90)
		(property "Reference" "C220"
			(at 1.382268 42.044874 270)
			(unlocked yes)
			(layer "B.SilkS")
			(effects
				(font
					(size 0.635 0.4064)
					(thickness 0.1524)
				)
				(justify mirror)
			)
		)
		(property "Value" "VAL*"
			(at 0 3.718306 270)
			(unlocked yes)
			(layer "B.Fab")
			(hide yes)
			(effects
				(font
					(size 0.7874 0.5842)
					(thickness 0.127)
				)
				(justify mirror)
			)
		)
		(property "Tolerance" "TOL*"
			(at 0 4.861306 270)
			(unlocked yes)
			(layer "Cmts.User")
			(hide yes)
			(effects
				(font
					(size 0.7874 0.5842)
					(thickness 0.127)
				)
				(justify mirror)
			)
		)
		(property "User Part Number" "PARTNUM*"
			(at 0 2.575306 270)
			(unlocked yes)
			(layer "Cmts.User")
			(hide yes)
			(effects
				(font
					(size 0.7874 0.5842)
					(thickness 0.127)
				)
				(justify mirror)
			)
		)
		(property "Device Type" "CAPACITOR-G105-0B104-CK,0.1UF,A"
			(at 0 1.432306 270)
			(unlocked yes)
			(layer "B.Fab")
			(hide yes)
			(effects
				(font
					(size 0.7874 0.5842)
					(thickness 0.127)
				)
				(justify mirror)
			)
		)
		(duplicate_pad_numbers_are_jumpers no)
		(fp_line
			(start -0.970026 0.4699)
			(end 0.970026 0.4699)
			(stroke
				(width 0.1)
				(type default)
			)
			(layer "B.SilkS")
		)
		(fp_line
			(start 0.970026 0.4699)
			(end 0.970026 -0.4699)
			(stroke
				(width 0.1)
				(type default)
			)
			(layer "B.SilkS")
		)
		(fp_line
			(start -0.970026 -0.4699)
			(end -0.970026 0.4699)
			(stroke
				(width 0.1)
				(type default)
			)
			(layer "B.SilkS")
		)
		(fp_line
			(start 0.970026 -0.4699)
			(end -0.970026 -0.4699)
			(stroke
				(width 0.1)
				(type default)
			)
			(layer "B.SilkS")
		)
		(fp_poly
			(pts
				(xy 0.970026 0.4699) (xy -0.970026 0.4699) (xy -0.970026 -0.4699) (xy 0.970026 -0.4699)
			)
			(stroke
				(width 0)
				(type default)
			)
			(fill no)
			(layer "B.CrtYd")
		)
		(fp_line
			(start -0.508 0.3048)
			(end 0.508 0.3048)
			(stroke
				(width 0.1)
				(type default)
			)
			(layer "B.Fab")
		)
		(fp_line
			(start 0.508 0.3048)
			(end 0.508 -0.3048)
			(stroke
				(width 0.1)
				(type default)
			)
			(layer "B.Fab")
		)
		(fp_line
			(start -0.508 -0.3048)
			(end -0.508 0.3048)
			(stroke
				(width 0.1)
				(type default)
			)
			(layer "B.Fab")
		)
		(fp_line
			(start 0.508 -0.3048)
			(end -0.508 -0.3048)
			(stroke
				(width 0.1)
				(type default)
			)
			(layer "B.Fab")
		)
		(pad "1" smd circle
			(at 0.500126 0 90)
			(size 0.635 0.635)
			(layers "B.Cu" "B.Mask" "B.Paste")
			(net "XP2R5V_FPGA")
		)
		(pad "2" smd circle
			(at -0.500126 0 90)
			(size 0.635 0.635)
			(layers "B.Cu" "B.Mask" "B.Paste")
			(net "SG")
		)
	)
	(footprint ""
		(layer "B.Cu")
		(at 95.631 -83.312)
		(property "Reference" "R200"
			(at -0.254 -5.54863 0)
			(unlocked yes)
			(layer "B.SilkS")
			(effects
				(font
					(size 0.7874 0.5842)
					(thickness 0.1524)
				)
				(justify mirror)
			)
		)
		(property "Value" "VAL*"
			(at -0.02032 2.13233 0)
			(unlocked yes)
			(layer "B.Fab")
			(hide yes)
			(effects
				(font
					(size 0.7874 0.5842)
					(thickness 0.1524)
				)
				(justify mirror)
			)
		)
		(property "Tolerance" "TOL*"
			(at -0.044704 3.05435 0)
			(unlocked yes)
			(layer "Cmts.User")
			(hide yes)
			(effects
				(font
					(size 0.7874 0.5842)
					(thickness 0.1524)
				)
				(justify mirror)
			)
		)
		(property "User Part Number" "PARTNUM*"
			(at -0.02032 4.024884 0)
			(unlocked yes)
			(layer "Cmts.User")
			(hide yes)
			(effects
				(font
					(size 0.7874 0.5842)
					(thickness 0.1524)
				)
				(justify mirror)
			)
		)
		(property "Device Type" "RESISTOR-G155-14701-01,4.7KOHMA"
			(at -0.008382 1.210564 0)
			(unlocked yes)
			(layer "B.Fab")
			(hide yes)
			(effects
				(font
					(size 0.7874 0.5842)
					(thickness 0.1524)
				)
				(justify mirror)
			)
		)
		(duplicate_pad_numbers_are_jumpers no)
		(fp_line
			(start -1.143 -0.5588)
			(end 1.143 -0.5588)
			(stroke
				(width 0.1)
				(type default)
			)
			(layer "B.SilkS")
		)
		(fp_line
			(start -1.143 0.5588)
			(end -1.143 -0.5588)
			(stroke
				(width 0.1)
				(type default)
			)
			(layer "B.SilkS")
		)
		(fp_line
			(start 1.143 -0.5588)
			(end 1.143 0.5588)
			(stroke
				(width 0.1)
				(type default)
			)
			(layer "B.SilkS")
		)
		(fp_line
			(start 1.143 0.5588)
			(end -1.143 0.5588)
			(stroke
				(width 0.1)
				(type default)
			)
			(layer "B.SilkS")
		)
		(fp_rect
			(start -1.143 0.5588)
			(end 1.143 -0.5588)
			(stroke
				(width 0)
				(type default)
			)
			(fill no)
			(layer "B.CrtYd")
		)
		(fp_line
			(start -0.508 -0.3048)
			(end 0.508 -0.3048)
			(stroke
				(width 0.1)
				(type default)
			)
			(layer "B.Fab")
		)
		(fp_line
			(start -0.508 0.3048)
			(end -0.508 -0.3048)
			(stroke
				(width 0.1)
				(type default)
			)
			(layer "B.Fab")
		)
		(fp_line
			(start 0.508 -0.3048)
			(end 0.508 0.3048)
			(stroke
				(width 0.1)
				(type default)
			)
			(layer "B.Fab")
		)
		(fp_line
			(start 0.508 0.3048)
			(end -0.508 0.3048)
			(stroke
				(width 0.1)
				(type default)
			)
			(layer "B.Fab")
		)
		(pad "1" smd rect
			(at 0.5334 0 180)
			(size 0.7112 0.6096)
			(layers "B.Cu" "B.Mask" "B.Paste")
			(net "UNNAMED_127_MT25QL128ABA1ESES_1")
		)
		(pad "2" smd rect
			(at -0.5334 0 180)
			(size 0.7112 0.6096)
			(layers "B.Cu" "B.Mask" "B.Paste")
			(net "XP3R3V_FPGA")
		)
		(zone
			(layer "B.Cu")
			(hatch none 0.5)
			(connect_pads
				(clearance 0)
			)
			(min_thickness 0.25)
			(keepout
				(tracks allowed)
				(vias not_allowed)
				(pads allowed)
				(copperpour not_allowed)
				(footprints allowed)
			)
			(placement
				(enabled no)
				(sheetname "")
			)
			(fill
				(thermal_gap 0.5)
				(thermal_bridge_width 0.5)
				(island_removal_mode 0)
			)
			(polygon
				(pts
					(xy 95.5548 -83.0072) (xy 95.7072 -83.0072) (xy 95.7072 -83.6168) (xy 95.5548 -83.6168)
				)
			)
		)
	)
)
